# T6G (Grand Teton) — schematic netlist excerpt (pin names and nets, part order shuffled) for the footprints in the layout excerpt that follows; sources: Cadence DE-HDL packaged netlist, KiCad conversion of 04192023_DAF0TMB3IC0_F0TG_MB_C_brd_V02_OCP.brd

J117  PICOPROBE_BXA  DELTA-L 4.0 EMPTY  pkg TRIANG_LAUNCH_3PXB  page 229
  \1_p\  = DELTA_L_85_5INCH_IN6_DN
  \2_n\  = DELTA_L_85_5INCH_IN6_DP
  \3_g\  = DELTA_L_GND_1

(kicad_pcb
	(version 20260206)
	(generator "pcbnew")
	(generator_version "10.0")
	(general
		(thickness 1.6)
		(legacy_teardrops no)
	)
	(paper "A4")
	(title_block
		(title "04192023_DAF0TMB3IC0_F0TG_MB_C_brd_V02_OCP.brd")
		(comment 1 "Grand Teton / footprints 5890-5890 of 8354")
	)
	(layers
		(0 "F.Cu" signal "TOP")
		(4 "In1.Cu" signal "GND")
		(6 "In2.Cu" signal "IN1")
		(8 "In3.Cu" signal "GND1")
		(10 "In4.Cu" signal "IN2")
		(12 "In5.Cu" signal "GND2")
		(14 "In6.Cu" signal "IN3")
		(16 "In7.Cu" signal "GND3")
		(18 "In8.Cu" signal "VCC")
		(20 "In9.Cu" signal "VCC1")
		(22 "In10.Cu" signal "GND4")
		(24 "In11.Cu" signal "IN4")
		(26 "In12.Cu" signal "GND5")
		(28 "In13.Cu" signal "IN5")
		(30 "In14.Cu" signal "GND6")
		(32 "In15.Cu" signal "IN6")
		(34 "In16.Cu" signal "GND7")
		(2 "B.Cu" signal "BOTTOM")
		(9 "F.Adhes" user "F.Adhesive")
		(11 "B.Adhes" user "B.Adhesive")
		(13 "F.Paste" user "Package Geometry/Pastemask Top")
		(15 "B.Paste" user "Package Geometry/Pastemask Bottom")
		(5 "F.SilkS" user "Ref Des/Silkscreen Top")
		(7 "B.SilkS" user "Ref Des/Silkscreen Bottom")
		(1 "F.Mask" user "Board Geometry/Soldermask Top")
		(3 "B.Mask" user "Board Geometry/Soldermask Bottom")
		(17 "Dwgs.User" user "User.Drawings")
		(19 "Cmts.User" user "User.Comments")
		(21 "Eco1.User" user "User.Eco1")
		(23 "Eco2.User" user "User.Eco2")
		(25 "Edge.Cuts" user "Board Geometry/Outline")
		(27 "Margin" user)
		(31 "F.CrtYd" user "Package Geometry/Place Bound Top")
		(29 "B.CrtYd" user "Package Geometry/Place Bound Bottom")
		(35 "F.Fab" user "Ref Des/Assembly Top")
		(33 "B.Fab" user "Ref Des/Assembly Bottom")
	)
	(footprint ""
		(layer "B.Cu")
		(at 366.288574 -2.537206)
		(property "Reference" "J117"
			(at 4.34594 1.464056 270)
			(unlocked yes)
			(layer "B.SilkS")
			(effects
				(font
					(size 0.7874 0.5842)
					(thickness 0.1524)
				)
				(justify left mirror)
			)
		)
		(property "Value" ""
			(at 0 0 0)
			(layer "B.Fab")
			(effects
				(font
					(size 1.27 1.27)
				)
				(justify mirror)
			)
		)
		(duplicate_pad_numbers_are_jumpers no)
		(fp_line
			(start -1.2192 -2.06756)
			(end -1.2192 2.06756)
			(stroke
				(width 0.1524)
				(type default)
			)
			(layer "B.SilkS")
		)
		(fp_line
			(start -1.2192 2.06756)
			(end 1.2192 2.06756)
			(stroke
				(width 0.1524)
				(type default)
			)
			(layer "B.SilkS")
		)
		(fp_line
			(start 1.2192 -2.06756)
			(end -1.2192 -2.06756)
			(stroke
				(width 0.1524)
				(type default)
			)
			(layer "B.SilkS")
		)
		(fp_line
			(start 1.2192 2.06756)
			(end 1.2192 -2.06756)
			(stroke
				(width 0.1524)
				(type default)
			)
			(layer "B.SilkS")
		)
		(pad "" np_thru_hole circle
			(at -3.4671 -1.27 270)
			(size 1.0414 1.0414)
			(drill 1.0414)
			(layers "*.Cu" "*.Mask")
			(clearance 0.381)
			(thermal_gap 0.381)
		)
		(pad "" np_thru_hole circle
			(at -3.4671 1.27 270)
			(size 1.0414 1.0414)
			(drill 1.0414)
			(layers "*.Cu" "*.Mask")
			(clearance 0.381)
			(thermal_gap 0.381)
		)
		(pad "" np_thru_hole circle
			(at 2.8829 -1.27 270)
			(size 1.0414 1.0414)
			(drill 1.0414)
			(layers "*.Cu" "*.Mask")
			(clearance 0.381)
			(thermal_gap 0.381)
		)
		(pad "" np_thru_hole circle
			(at 2.8829 1.27 270)
			(size 1.0414 1.0414)
			(drill 1.0414)
			(layers "*.Cu" "*.Mask")
			(clearance 0.381)
			(thermal_gap 0.381)
		)
		(pad "1" smd rect
			(at -0.8255 -0.249936 270)
			(size 0.3048 0.508)
			(layers "B.Cu" "B.Mask" "B.Paste")
			(net "DELTA_L_85_5INCH_IN6_DN")
		)
		(pad "2" smd rect
			(at -0.8255 0.249936 270)
			(size 0.3048 0.508)
			(layers "B.Cu" "B.Mask" "B.Paste")
			(net "DELTA_L_85_5INCH_IN6_DP")
		)
		(pad "3" smd circle
			(at 0 0 180)
			(size 0 0)
			(layers "B.Cu" "B.Mask" "B.Paste")
			(net "DELTA_L_GND_1")
		)
		(zone
			(layers "F.Cu" "B.Cu" "In1.Cu" "In2.Cu" "In3.Cu" "In4.Cu" "In5.Cu" "In6.Cu"
				"In7.Cu" "In8.Cu" "In9.Cu" "In10.Cu" "In11.Cu" "In12.Cu" "In13.Cu" "In14.Cu"
				"In15.Cu" "In16.Cu"
			)
			(hatch none 0.5)
			(connect_pads
				(clearance 0)
			)
			(min_thickness 0.25)
			(keepout
				(tracks not_allowed)
				(vias allowed)
				(pads allowed)
				(copperpour not_allowed)
				(footprints allowed)
			)
			(placement
				(enabled no)
				(sheetname "")
			)
			(fill
				(thermal_gap 0.5)
				(thermal_bridge_width 0.5)
				(island_removal_mode 0)
			)
			(polygon
				(pts
					(arc
						(start 363.748574 -3.807206)
						(mid 361.894374 -3.807206)
						(end 363.748574 -3.807206)
					)
				)
			)
		)
		(zone
			(layers "F.Cu" "B.Cu" "In1.Cu" "In2.Cu" "In3.Cu" "In4.Cu" "In5.Cu" "In6.Cu"
				"In7.Cu" "In8.Cu" "In9.Cu" "In10.Cu" "In11.Cu" "In12.Cu" "In13.Cu" "In14.Cu"
				"In15.Cu" "In16.Cu"
			)
			(hatch none 0.5)
			(connect_pads
				(clearance 0)
			)
			(min_thickness 0.25)
			(keepout
				(tracks not_allowed)
				(vias allowed)
				(pads allowed)
				(copperpour not_allowed)
				(footprints allowed)
			)
			(placement
				(enabled no)
				(sheetname "")
			)
			(fill
				(thermal_gap 0.5)
				(thermal_bridge_width 0.5)
				(island_removal_mode 0)
			)
			(polygon
				(pts
					(arc
						(start 363.748574 -1.267206)
						(mid 361.894374 -1.267206)
						(end 363.748574 -1.267206)
					)
				)
			)
		)
		(zone
			(layers "F.Cu" "B.Cu" "In1.Cu" "In2.Cu" "In3.Cu" "In4.Cu" "In5.Cu" "In6.Cu"
				"In7.Cu" "In8.Cu" "In9.Cu" "In10.Cu" "In11.Cu" "In12.Cu" "In13.Cu" "In14.Cu"
				"In15.Cu" "In16.Cu"
			)
			(hatch none 0.5)
			(connect_pads
				(clearance 0)
			)
			(min_thickness 0.25)
			(keepout
				(tracks not_allowed)
				(vias allowed)
				(pads allowed)
				(copperpour not_allowed)
				(footprints allowed)
			)
			(placement
				(enabled no)
				(sheetname "")
			)
			(fill
				(thermal_gap 0.5)
				(thermal_bridge_width 0.5)
				(island_removal_mode 0)
			)
			(polygon
				(pts
					(arc
						(start 370.098574 -3.807206)
						(mid 368.244374 -3.807206)
						(end 370.098574 -3.807206)
					)
				)
			)
		)
		(zone
			(layers "F.Cu" "B.Cu" "In1.Cu" "In2.Cu" "In3.Cu" "In4.Cu" "In5.Cu" "In6.Cu"
				"In7.Cu" "In8.Cu" "In9.Cu" "In10.Cu" "In11.Cu" "In12.Cu" "In13.Cu" "In14.Cu"
				"In15.Cu" "In16.Cu"
			)
			(hatch none 0.5)
			(connect_pads
				(clearance 0)
			)
			(min_thickness 0.25)
			(keepout
				(tracks not_allowed)
				(vias allowed)
				(pads allowed)
				(copperpour not_allowed)
				(footprints allowed)
			)
			(placement
				(enabled no)
				(sheetname "")
			)
			(fill
				(thermal_gap 0.5)
				(thermal_bridge_width 0.5)
				(island_removal_mode 0)
			)
			(polygon
				(pts
					(arc
						(start 370.098574 -1.267206)
						(mid 368.244374 -1.267206)
						(end 370.098574 -1.267206)
					)
				)
			)
		)
		(zone
			(layer "B.Cu")
			(hatch none 0.5)
			(connect_pads
				(clearance 0)
			)
			(min_thickness 0.25)
			(keepout
				(tracks not_allowed)
				(vias allowed)
				(pads allowed)
				(copperpour not_allowed)
				(footprints allowed)
			)
			(placement
				(enabled no)
				(sheetname "")
			)
			(fill
				(thermal_gap 0.5)
				(thermal_bridge_width 0.5)
				(island_removal_mode 0)
			)
			(polygon
				(pts
					(xy 365.170974 -3.085846) (xy 365.170974 -2.990342) (xy 365.767874 -2.990342) (xy 365.767874 -2.583942)
					(xy 365.170974 -2.583942) (xy 365.170974 -2.49047) (xy 365.767874 -2.49047) (xy 365.767874 -2.08407)
					(xy 365.170974 -2.08407) (xy 365.170974 -1.988566) (xy 365.869474 -1.988566) (xy 365.869474 -3.085846)
				)
			)
		)
	)
)
